# T6G (Grand Teton) — schematic netlist excerpt (pin names and nets, part order shuffled) for the footprints in the layout excerpt that follows; sources: Cadence DE-HDL packaged netlist, KiCad conversion of 04192023_DAF0TMB3IC0_F0TG_MB_C_brd_V02_OCP.brd

R6210  Q_RES  0 5% CHIP  pkg 0402LF  page 267 : A = HSC_CSOUT ; B = HSC_D_OC
R6240  Q_RES  0 5% CHIP  pkg 0402LF  page 270 : A = PWRGD_P1V8_AUX_R ; B = P1V2_AUX_ENABLE

(kicad_pcb
	(version 20260206)
	(generator "pcbnew")
	(generator_version "10.0")
	(general
		(thickness 1.6)
		(legacy_teardrops no)
	)
	(paper "A4")
	(title_block
		(title "04192023_DAF0TMB3IC0_F0TG_MB_C_brd_V02_OCP.brd")
		(comment 1 "Grand Teton / footprints 8317-8318 of 8354")
	)
	(layers
		(0 "F.Cu" signal "TOP")
		(4 "In1.Cu" signal "GND")
		(6 "In2.Cu" signal "IN1")
		(8 "In3.Cu" signal "GND1")
		(10 "In4.Cu" signal "IN2")
		(12 "In5.Cu" signal "GND2")
		(14 "In6.Cu" signal "IN3")
		(16 "In7.Cu" signal "GND3")
		(18 "In8.Cu" signal "VCC")
		(20 "In9.Cu" signal "VCC1")
		(22 "In10.Cu" signal "GND4")
		(24 "In11.Cu" signal "IN4")
		(26 "In12.Cu" signal "GND5")
		(28 "In13.Cu" signal "IN5")
		(30 "In14.Cu" signal "GND6")
		(32 "In15.Cu" signal "IN6")
		(34 "In16.Cu" signal "GND7")
		(2 "B.Cu" signal "BOTTOM")
		(9 "F.Adhes" user "F.Adhesive")
		(11 "B.Adhes" user "B.Adhesive")
		(13 "F.Paste" user "Package Geometry/Pastemask Top")
		(15 "B.Paste" user "Package Geometry/Pastemask Bottom")
		(5 "F.SilkS" user "Ref Des/Silkscreen Top")
		(7 "B.SilkS" user "Ref Des/Silkscreen Bottom")
		(1 "F.Mask" user "Board Geometry/Soldermask Top")
		(3 "B.Mask" user "Board Geometry/Soldermask Bottom")
		(17 "Dwgs.User" user "User.Drawings")
		(19 "Cmts.User" user "User.Comments")
		(21 "Eco1.User" user "User.Eco1")
		(23 "Eco2.User" user "User.Eco2")
		(25 "Edge.Cuts" user "Board Geometry/Outline")
		(27 "Margin" user)
		(31 "F.CrtYd" user "Package Geometry/Place Bound Top")
		(29 "B.CrtYd" user "Package Geometry/Place Bound Bottom")
		(35 "F.Fab" user "Ref Des/Assembly Top")
		(33 "B.Fab" user "Ref Des/Assembly Bottom")
	)
	(footprint ""
		(layer "B.Cu")
		(at 121.010172 -72.566022)
		(property "Reference" "R6240"
			(at 0 0 0)
			(layer "B.SilkS")
			(hide yes)
			(effects
				(font
					(size 1.27 1.27)
				)
				(justify mirror)
			)
		)
		(property "Value" ""
			(at 0 0 0)
			(layer "B.Fab")
			(effects
				(font
					(size 1.27 1.27)
				)
				(justify mirror)
			)
		)
		(duplicate_pad_numbers_are_jumpers no)
		(fp_line
			(start -0.7874 -0.4064)
			(end -0.7874 0.4064)
			(stroke
				(width 0.1524)
				(type default)
			)
			(layer "B.SilkS")
		)
		(fp_line
			(start -0.7874 0.4064)
			(end 0.7874 0.4064)
			(stroke
				(width 0.1524)
				(type default)
			)
			(layer "B.SilkS")
		)
		(fp_line
			(start 0.7874 -0.4064)
			(end -0.7874 -0.4064)
			(stroke
				(width 0.1524)
				(type default)
			)
			(layer "B.SilkS")
		)
		(fp_line
			(start 0.7874 0.4064)
			(end 0.7874 -0.4064)
			(stroke
				(width 0.1524)
				(type default)
			)
			(layer "B.SilkS")
		)
		(fp_line
			(start -0.67945 -0.3048)
			(end -0.67945 0.3048)
			(stroke
				(width 0.1)
				(type default)
			)
			(layer "B.Fab")
		)
		(fp_line
			(start -0.67945 0.3048)
			(end -0.120396 0.3048)
			(stroke
				(width 0.1)
				(type default)
			)
			(layer "B.Fab")
		)
		(fp_line
			(start -0.12065 -0.3048)
			(end -0.67945 -0.3048)
			(stroke
				(width 0.1)
				(type default)
			)
			(layer "B.Fab")
		)
		(fp_line
			(start -0.12065 -0.2794)
			(end -0.12065 -0.3048)
			(stroke
				(width 0.1)
				(type default)
			)
			(layer "B.Fab")
		)
		(fp_line
			(start -0.120396 0.2794)
			(end 0.12065 0.2794)
			(stroke
				(width 0.1)
				(type default)
			)
			(layer "B.Fab")
		)
		(fp_line
			(start -0.120396 0.3048)
			(end -0.120396 0.2794)
			(stroke
				(width 0.1)
				(type default)
			)
			(layer "B.Fab")
		)
		(fp_line
			(start 0.12065 -0.305054)
			(end 0.12065 -0.2794)
			(stroke
				(width 0.1)
				(type default)
			)
			(layer "B.Fab")
		)
		(fp_line
			(start 0.12065 -0.2794)
			(end -0.12065 -0.2794)
			(stroke
				(width 0.1)
				(type default)
			)
			(layer "B.Fab")
		)
		(fp_line
			(start 0.12065 0.2794)
			(end 0.12065 0.3048)
			(stroke
				(width 0.1)
				(type default)
			)
			(layer "B.Fab")
		)
		(fp_line
			(start 0.12065 0.3048)
			(end 0.67945 0.3048)
			(stroke
				(width 0.1)
				(type default)
			)
			(layer "B.Fab")
		)
		(fp_line
			(start 0.67945 -0.305054)
			(end 0.12065 -0.305054)
			(stroke
				(width 0.1)
				(type default)
			)
			(layer "B.Fab")
		)
		(fp_line
			(start 0.67945 0.3048)
			(end 0.67945 -0.305054)
			(stroke
				(width 0.1)
				(type default)
			)
			(layer "B.Fab")
		)
		(pad "1" smd circle
			(at 0.40005 0 180)
			(size 0 0)
			(layers "B.Cu" "B.Mask" "B.Paste")
			(net "PWRGD_P1V8_AUX_R")
		)
		(pad "2" smd circle
			(at -0.40005 0 180)
			(size 0 0)
			(layers "B.Cu" "B.Mask" "B.Paste")
			(net "P1V2_AUX_ENABLE")
		)
	)
	(footprint ""
		(layer "B.Cu")
		(at 177.278284 -421.217598)
		(property "Reference" "R6210"
			(at 0 0 0)
			(layer "B.SilkS")
			(hide yes)
			(effects
				(font
					(size 1.27 1.27)
				)
				(justify mirror)
			)
		)
		(property "Value" ""
			(at 0 0 0)
			(layer "B.Fab")
			(effects
				(font
					(size 1.27 1.27)
				)
				(justify mirror)
			)
		)
		(duplicate_pad_numbers_are_jumpers no)
		(fp_line
			(start -0.7874 -0.4064)
			(end -0.7874 0.4064)
			(stroke
				(width 0.1524)
				(type default)
			)
			(layer "B.SilkS")
		)
		(fp_line
			(start -0.7874 0.4064)
			(end 0.7874 0.4064)
			(stroke
				(width 0.1524)
				(type default)
			)
			(layer "B.SilkS")
		)
		(fp_line
			(start 0.7874 -0.4064)
			(end -0.7874 -0.4064)
			(stroke
				(width 0.1524)
				(type default)
			)
			(layer "B.SilkS")
		)
		(fp_line
			(start 0.7874 0.4064)
			(end 0.7874 -0.4064)
			(stroke
				(width 0.1524)
				(type default)
			)
			(layer "B.SilkS")
		)
		(fp_line
			(start -0.67945 -0.3048)
			(end -0.67945 0.3048)
			(stroke
				(width 0.1)
				(type default)
			)
			(layer "B.Fab")
		)
		(fp_line
			(start -0.67945 0.3048)
			(end -0.120396 0.3048)
			(stroke
				(width 0.1)
				(type default)
			)
			(layer "B.Fab")
		)
		(fp_line
			(start -0.12065 -0.3048)
			(end -0.67945 -0.3048)
			(stroke
				(width 0.1)
				(type default)
			)
			(layer "B.Fab")
		)
		(fp_line
			(start -0.12065 -0.2794)
			(end -0.12065 -0.3048)
			(stroke
				(width 0.1)
				(type default)
			)
			(layer "B.Fab")
		)
		(fp_line
			(start -0.120396 0.2794)
			(end 0.12065 0.2794)
			(stroke
				(width 0.1)
				(type default)
			)
			(layer "B.Fab")
		)
		(fp_line
			(start -0.120396 0.3048)
			(end -0.120396 0.2794)
			(stroke
				(width 0.1)
				(type default)
			)
			(layer "B.Fab")
		)
		(fp_line
			(start 0.12065 -0.305054)
			(end 0.12065 -0.2794)
			(stroke
				(width 0.1)
				(type default)
			)
			(layer "B.Fab")
		)
		(fp_line
			(start 0.12065 -0.2794)
			(end -0.12065 -0.2794)
			(stroke
				(width 0.1)
				(type default)
			)
			(layer "B.Fab")
		)
		(fp_line
			(start 0.12065 0.2794)
			(end 0.12065 0.3048)
			(stroke
				(width 0.1)
				(type default)
			)
			(layer "B.Fab")
		)
		(fp_line
			(start 0.12065 0.3048)
			(end 0.67945 0.3048)
			(stroke
				(width 0.1)
				(type default)
			)
			(layer "B.Fab")
		)
		(fp_line
			(start 0.67945 -0.305054)
			(end 0.12065 -0.305054)
			(stroke
				(width 0.1)
				(type default)
			)
			(layer "B.Fab")
		)
		(fp_line
			(start 0.67945 0.3048)
			(end 0.67945 -0.305054)
			(stroke
				(width 0.1)
				(type default)
			)
			(layer "B.Fab")
		)
		(pad "1" smd circle
			(at 0.40005 0 180)
			(size 0 0)
			(layers "B.Cu" "B.Mask" "B.Paste")
			(net "HSC_CSOUT")
		)
		(pad "2" smd circle
			(at -0.40005 0 180)
			(size 0 0)
			(layers "B.Cu" "B.Mask" "B.Paste")
			(net "HSC_D_OC")
		)
	)
)
